FILE_TYPE = CONNECTIVITY;
{Allegro Design Entry HDL 16.6-p007 (v16-6-112F) 10/10/2012}
"PAGE_NUMBER" = 203;
0"NC";
1"GND\g";
2"GND\g";
3"GND\g";
4"GND\g";
5"PVCCIN_CPU0\g";
6"PVCCIN_CPU0\g";
7"GND\g";
8"GND\g";
9"GND\g";
10"GND\g";
11"PVCCIN_CPU0\g";
12"VR_FET_SW_P12V_STBY_PVCCIN_CPU0\g";
13"GND\g";
14"VR_FET_SW_P12V_STBY_PVCCIN_CPU0\g";
15"GND\g";
16"GND\g";
17"P5V_STBY\g";
18"P5V_STBY\g";
19"GND\g";
20"GND\g";
21"GND\g";
22"GND\g";
23"A_TSENSE_PVCCIN_CPU0";
24"ISENSE_PVCCIN_CPU0_PH4_IMON";
25"VR_PVCCIN_CPU0_PH3_PHASE"VOLTAGE"5";
26"VR_PVCCIN_CPU0_PH3_BOOT";
27"VR_PVCCIN_CPU0_PWM3";
28"VR_PVCCIN_CPU0_AIREF3";
29"VR_PVCCIN_CPU0_AIREF4";
30"VR_PVCCIN_CPU0_PH4_OCSET"VOLTAGE"3.6";
31"TP_PVCCIN_CPU0_PH4_GL_0";
32"VR_PVCCIN_CPU0_PWM4";
33"VR_PVCCIN_CPU0_PHASE4"VOLTAGE"5";
34"VR_PVCCIN_CPU0_PHASE3_RC";
35"VR_PVCCIN_CPU0_PH3_OCSET"VOLTAGE"3.6";
36"VR_PVCCIN_CPU0_PHASE3"VOLTAGE"5";
37"TP_PVCCIN_CPU0_PH4_GL_1";
38"VR_PVCCIN_CPU0_PH4_VCIN"VOLTAGE"5";
39"VR_PVCCIN_CPU0_PH3_BOOT_R";
40"VR_PVCCIN_CPU0_PH3_VCIN";
41"VR_PVCCIN_CPU0_PHASE4_RC";
42"VR_PVCCIN_CPU0_PH4_BOOT_R";
43"VR_PVCCIN_CPU0_PH4_PHASE"VOLTAGE"5";
44"TP_PVCCIN_CPU0_PH3_GL_0";
45"TP_PVCCIN_CPU0_PH3_GL_1";
46"A_TSENSE_PVCCIN_CPU0";
47"VR_PVCCIN_CPU0_PH4_BOOT";
48"ISENSE_PVCCIN_CPU0_PH3_IMON";
%"CAP"
"1","(-6350,4175)","0","mstr_discrete","I1";
;
CDS_SEC"1"
CDS_LOCATION"C6P24"
LOCATION"C6P24"
VALUE"10UF"
VOLTAGE"16V"
PACK_TYPE"0805"
MATERIAL"X6S"
PART_NUMBER"C95333-007"
TOLERANCE"10%"
SEC"1"
SEC_TYPE"0805"
ROOM"PVCCIN_CPU0_PWR_VR"
CDS_LIB"mstr_discrete";
"A"
$PN"1"12;
"B"
$PN"2"13;
%"GND"
"1","(-1975,3775)","0","mstr_symbols","I100";
;
HDL_POWER"GND"
BODY_TYPE"PLUMBING"
CDS_LIB"mstr_symbols"
SIZE"1B"
VOLTAGE"0"
ROOM"VDDQ_KLM_PWR_VR";
"A\NAC"1;
%"GND"
"1","(-1950,3000)","0","mstr_symbols","I103";
;
HDL_POWER"GND"
BODY_TYPE"PLUMBING"
CDS_LIB"mstr_symbols"
ROOM"PVCCIN_CPU0_PWR_VR"
BOM_COST"PROC_VRD_VCCIN_CPU0"
VOLTAGE"0"
SIZE"1B";
"A\NAC"2;
%"GND"
"1","(-1975,350)","0","mstr_symbols","I104";
;
HDL_POWER"GND"
BODY_TYPE"PLUMBING"
CDS_LIB"mstr_symbols"
SIZE"1B"
VOLTAGE"0"
BOM_COST"PROC_VRD_VCCIN_CPU0"
ROOM"PVCCIN_CPU0_PWR_VR";
"A\NAC"3;
%"GND"
"1","(-1925,1075)","0","mstr_symbols","I107";
;
HDL_POWER"GND"
BODY_TYPE"PLUMBING"
SIZE"1B"
VOLTAGE"0"
ROOM"VDDQ_KLM_PWR_VR"
CDS_LIB"mstr_symbols";
"A\NAC"4;
%"CAP"
"1","(-1925,1275)","0","mstr_discrete","I108";
;
CDS_SEC"1"
CDS_LOCATION"CT42"
LOCATION"CT42"
POP"NOPOP"
VALUE"1000PF"
VOLTAGE"50V"
TOLERANCE"10%"
MATERIAL"X7R"
PART_NUMBER"A36096-046"
PACK_TYPE"0402LF"
SEC_TYPE"0402LF"
SEC"1"
CDS_LIB"mstr_discrete"
ROOM"VDDQ_KLM_PWR_VR";
"A"
$PN"1"23;
"B"
$PN"2"4;
%"PVCCIN_CPU0"
"1","(-450,1025)","0","mstr_symbols","I109";
;
CDS_LIB"mstr_symbols"
VOLTAGE"2.0V"
BODY_TYPE"PLUMBING"
HDL_POWER"PVCCIN_CPU0";
"G\NAC"5;
%"CAP"
"1","(-1950,3500)","0","mstr_discrete","I118";
;
CDS_SEC"1"
CDS_LOCATION"CT38"
POP"NOPOP"
MATERIAL"X7R"
PART_NUMBER"A36096-046"
VALUE"1000PF"
LOCATION"CT38"
VOLTAGE"50V"
PACK_TYPE"0402LF"
TOLERANCE"10%"
SEC_TYPE"0402LF"
SEC"1"
ROOM"VDDQ_KLM_PWR_VR"
CDS_LIB"mstr_discrete";
"A"
$PN"1"36;
"B"
$PN"2"34;
%"CAP"
"1","(-1975,800)","0","mstr_discrete","I119";
;
CDS_SEC"1"
CDS_LOCATION"CT41"
PACK_TYPE"0402LF"
PART_NUMBER"A36096-046"
TOLERANCE"10%"
MATERIAL"X7R"
VOLTAGE"50V"
POP"NOPOP"
LOCATION"CT41"
VALUE"1000PF"
SEC_TYPE"0402LF"
SEC"1"
ROOM"VDDQ_KLM_PWR_VR"
CDS_LIB"mstr_discrete";
"A"
$PN"1"33;
"B"
$PN"2"41;
%"PVCCIN_CPU0"
"1","(-500,3750)","0","mstr_symbols","I12";
;
VOLTAGE"2.0V"
CDS_LIB"mstr_symbols"
BODY_TYPE"PLUMBING"
HDL_POWER"PVCCIN_CPU0";
"G\NAC"6;
%"RES"
"1","(-4725,3725)","0","mstr_discrete","I122";
;
CDS_SEC"1"
CDS_LOCATION"RT25"
PACK_TYPE"0603"
LOCATION"RT25"
PART_NUMBER"G22178-002"
VALUE"0"
SEC"1"
MATERIAL"CHIP"
TOLERANCE"5.0%"
WATTAGE"1/10W"
ROOM"NIC_SPRV"
BOM_COST"NT_GBE_BASE"
CDS_LIB"mstr_discrete"
SEC_TYPE"0603";
"B"
$PN"2"39;
"A"
$PN"1"26;
%"RES"
"1","(-4950,975)","0","mstr_discrete","I123";
;
CDS_SEC"1"
CDS_LOCATION"RT28"
MATERIAL"CHIP"
PART_NUMBER"G22178-002"
PACK_TYPE"0603"
VALUE"0"
LOCATION"RT28"
TOLERANCE"5.0%"
WATTAGE"1/10W"
SEC_TYPE"0603"
SEC"1"
ROOM"NIC_SPRV"
BOM_COST"NT_GBE_BASE"
CDS_LIB"mstr_discrete";
"B"
$PN"2"42;
"A"
$PN"1"47;
%"RES"
"1","(-5325,4750)","0","mstr_discrete","I128";
;
MATERIAL"CHIP"
LOCATION"R6P19"
WATTAGE"1/16W"
TOLERANCE"5%"
PART_NUMBER"G21497-005"
PACK_TYPE"0402"
VALUE"0.0"
CDS_LOCATION"R6P19"
BOM_COST"PROC_SIDEBAND"
CDS_LIB"mstr_discrete"
SEC_TYPE"0402"
SEC"1"
ROOM"CPU0"
CDS_SEC"1";
"B"
$PN"2"17;
"A"
$PN"1"40;
%"RES"
"1","(-5425,2000)","0","mstr_discrete","I129";
;
WATTAGE"1/16W"
LOCATION"R6P10"
TOLERANCE"5%"
VALUE"0.0"
PART_NUMBER"G21497-005"
PACK_TYPE"0402"
MATERIAL"CHIP"
BOM_COST"PROC_SIDEBAND"
CDS_LIB"mstr_discrete"
SEC_TYPE"0402"
SEC"1"
ROOM"CPU0"
CDS_SEC"1"
CDS_LOCATION"R6P10";
"B"
$PN"2"18;
"A"
$PN"1"38;
%"IND-120NH-30-GP"
"1","(-1175,3675)","1","w_hdl","I130";
;
CDS_SEC"1"
CDS_LOCATION"L4D2"
TYPE"IRMS=66A@DELTA_T<40C"
LOCATION"L4D2"
VALUE"IND-120NH-30-GP"
ATTRIBUTE"120NH"
RATED"ISAT=94A@25C"
PACK_SIZE"DCR=0.17MOHM"
PACK_TYPE"DISCRET-GB2"
SEC"1"
SEC_TYPE"DISCRET-GB2"
CDS_LMAN_SYM_OUTLINE"-75,100,75,-100"
CDS_LIB"w_hdl"
PART_NUMBER"068.1202N.M001";
"F"
$PN"2"6;
"S"
$PN"1"36;
%"IND-120NH-30-GP"
"1","(-1075,950)","1","w_hdl","I131";
;
CDS_SEC"1"
CDS_LOCATION"L4D1"
PACK_SIZE"DCR=0.17MOHM"
ATTRIBUTE"120NH"
RATED"ISAT=94A@25C"
LOCATION"L4D1"
TYPE"IRMS=66A@DELTA_T<40C"
VALUE"IND-120NH-30-GP"
PART_NUMBER"068.1202N.M001"
CDS_LIB"w_hdl"
CDS_LMAN_SYM_OUTLINE"-75,100,75,-100"
SEC_TYPE"DISCRET-GB2"
SEC"1"
PACK_TYPE"DISCRET-GB2";
"F"
$PN"2"5;
"S"
$PN"1"33;
%"SC1U10V2KX-4-GP"
"1","(-5050,4150)","0","w_hdl","I132";
;
CDS_SEC"1"
CDS_LOCATION"C4D14"
PACK_SIZE"0402"
VALUE"SC1U10V2KX-4-GP"
LOCATION"C4D14"
ATTRIBUTE"1UF"
TOLERANCE"10%"
RATED"10V"
PACK_TYPE"SMD-BCG6"
SEC"1"
SEC_TYPE"SMD-BCG6"
CDS_LMAN_SYM_OUTLINE"-50,25,50,-25"
CDS_LIB"w_hdl"
PART_NUMBER"78.10523.8FL";
"2"
$PN"2"13;
"1"
$PN"1"17;
%"SC1U10V2KX-4-GP"
"1","(-5200,1475)","0","w_hdl","I133";
;
CDS_SEC"1"
CDS_LOCATION"C4D6"
PACK_SIZE"0402"
TOLERANCE"10%"
RATED"10V"
ATTRIBUTE"1UF"
VALUE"SC1U10V2KX-4-GP"
LOCATION"C4D6"
PACK_TYPE"SMD-BCG6"
SEC"1"
SEC_TYPE"SMD-BCG6"
PART_NUMBER"78.10523.8FL"
CDS_LIB"w_hdl"
CDS_LMAN_SYM_OUTLINE"-50,25,50,-25";
"2"
$PN"2"15;
"1"
$PN"1"18;
%"1R3F-GP"
"1","(-1950,3200)","0","w_hdl","I134";
;
CDS_SEC"1"
CDS_LOCATION"RT26"
RATED"1/10W"
LOCATION"RT26"
TOLERANCE"1%"
POP"NOPOP"
VALUE"1R3F-GP"
ATTRIBUTE"1 OHM"
PACK_SIZE"0603"
PACK_TYPE"RCL_GP"
SEC"1"
SEC_TYPE"RCL_GP"
PART_NUMBER"64.1R005.55L"
CDS_LIB"w_hdl"
CDS_LMAN_SYM_OUTLINE"-50,75,50,-75";
"2"
$PN"2"2;
"1"
$PN"1"34;
%"1R3F-GP"
"1","(-1975,550)","0","w_hdl","I135";
;
CDS_SEC"1"
CDS_LOCATION"RT27"
PACK_SIZE"0603"
VALUE"1R3F-GP"
ATTRIBUTE"1 OHM"
TOLERANCE"1%"
POP"NOPOP"
RATED"1/10W"
LOCATION"RT27"
CDS_LMAN_SYM_OUTLINE"-50,75,50,-75"
CDS_LIB"w_hdl"
PART_NUMBER"64.1R005.55L"
SEC_TYPE"RCL_GP"
SEC"1"
PACK_TYPE"RCL_GP";
"2"
$PN"2"3;
"1"
$PN"1"41;
%"GND"
"1","(-500,3100)","0","mstr_symbols","I14";
;
ROOM"PVCCIN_CPU0_PWR_VR"
BOM_COST"PROC_VRD_VCCIN_CPU0"
CDS_LIB"mstr_symbols"
VOLTAGE"0"
SIZE"1B"
BODY_TYPE"PLUMBING"
HDL_POWER"GND";
"A\NAC"7;
%"CAPP"
"1","(-925,2600)","0","mstr_discrete","I16";
;
CDS_SEC"1"
LOCATION"C6R3"
PART_NUMBER"699013-049"
PACK_TYPE"3018"
MATERIAL"ALUM"
VALUE"470UF"
TOLERANCE"20%"
VOLTAGE"2.5V"
GROUP"PWR_BULK_CAP"
SEC_TYPE"3018"
SEC"1"
ROOM"PVCCIN_CPU0_DECAP_VR"
BOM_COST"PROC_VRD_VCCIN_CPU0"
CDS_LOCATION"C6R3"
CDS_LIB"mstr_discrete";
"B"
$PN"2"8;
"A"
$PN"1"11;
%"GND"
"1","(-475,2225)","0","mstr_symbols","I17";
;
HDL_POWER"GND"
BODY_TYPE"PLUMBING"
VOLTAGE"0"
CDS_LIB"mstr_symbols"
SIZE"1B"
BOM_COST"PROC_VRD_VCCIN_CPU0"
ROOM"PVCCIN_CPU0_DECAP_VR";
"A\NAC"8;
%"CAPP"
"1","(-1400,2600)","0","mstr_discrete","I18";
;
CDS_SEC"1"
PACK_TYPE"3018"
LOCATION"C6R9"
TOLERANCE"20%"
PART_NUMBER"699013-049"
MATERIAL"ALUM"
VOLTAGE"2.5V"
VALUE"470UF"
GROUP"PWR_BULK_CAP"
SEC_TYPE"3018"
SEC"1"
BOM_COST"PROC_VRD_VCCIN_CPU0"
ROOM"PVCCIN_CPU0_DECAP_VR"
CDS_LOCATION"C6R9"
CDS_LIB"mstr_discrete";
"B"
$PN"2"8;
"A"
$PN"1"11;
%"CAP"
"1","(-6700,4175)","0","mstr_discrete","I2";
;
CDS_SEC"1"
PART_NUMBER"C95333-007"
MATERIAL"X6S"
TOLERANCE"10%"
VOLTAGE"16V"
VALUE"10UF"
LOCATION"C6R6"
PACK_TYPE"0805"
ROOM"PVCCIN_CPU0_PWR_VR"
SEC"1"
SEC_TYPE"0805"
CDS_LIB"mstr_discrete"
CDS_LOCATION"C6R6";
"A"
$PN"1"12;
"B"
$PN"2"13;
%"CAP_A"
"1","(-700,725)","0","dev_discrete","I25";
;
MATERIAL"X6S"
VALUE"22.0UF"
LOCATION"C6P3"
VOLTAGE"4V"
TOLERANCE"20%"
PART_NUMBER"E15431-004"
PACK_TYPE"0603V"
GROUP"PWR_MLCC_CAP"
CDS_LIB"dev_discrete"
ROOM"PVCCIN_CPU0_PWR_VR"
SEC"1"
SEC_TYPE"0603V"
CDS_SEC"1"
BOM_COST"PROC_VRD_VCCIN_CPU0"
CDS_LOCATION"C6P3";
"B"
$PN"2"9;
"A"
$PN"1"5;
%"GND"
"1","(-700,425)","0","mstr_symbols","I26";
;
HDL_POWER"GND"
BODY_TYPE"PLUMBING"
SIZE"1B"
VOLTAGE"0"
CDS_LIB"mstr_symbols"
BOM_COST"PROC_VRD_VCCIN_CPU0"
ROOM"PVCCIN_CPU0_PWR_VR";
"A\NAC"9;
%"GND"
"1","(-2475,3275)","0","mstr_symbols","I27";
;
HDL_POWER"GND"
BODY_TYPE"PLUMBING"
CDS_LIB"mstr_symbols"
SIZE"1B"
VOLTAGE"0"
BOM_COST"PROC_VRD_VCCIN_CPU0"
ROOM"PVCCIN_CPU0_PWR_VR";
"A\NAC"10;
%"CAPP"
"1","(-1850,2600)","0","mstr_discrete","I28";
;
CDS_SEC"1"
MATERIAL"ALUM"
VOLTAGE"2.5V"
LOCATION"C6P23"
VALUE"470UF"
PACK_TYPE"3018"
TOLERANCE"20%"
PART_NUMBER"699013-049"
GROUP"PWR_BULK_CAP"
SEC_TYPE"3018"
BOM_COST"PROC_VRD_VCCIN_CPU0"
SEC"1"
CDS_LOCATION"C6P23"
ROOM"PVCCIN_CPU0_DECAP_VR"
CDS_LIB"mstr_discrete";
"B"
$PN"2"8;
"A"
$PN"1"11;
%"CAPP"
"1","(-2300,2600)","0","mstr_discrete","I29";
;
CDS_SEC"1"
LOCATION"C6P14"
VALUE"470UF"
PACK_TYPE"3018"
MATERIAL"ALUM"
TOLERANCE"20%"
VOLTAGE"2.5V"
PART_NUMBER"699013-049"
GROUP"PWR_BULK_CAP"
SEC_TYPE"3018"
SEC"1"
BOM_COST"PROC_VRD_VCCIN_CPU0"
ROOM"PVCCIN_CPU0_DECAP_VR"
CDS_LOCATION"C6P14"
CDS_LIB"mstr_discrete";
"B"
$PN"2"8;
"A"
$PN"1"11;
%"CAP"
"1","(-5875,825)","2","mstr_discrete","I3";
;
CDS_SEC"1"
LOCATION"C4D9"
VALUE"0.220UF"
PART_NUMBER"A36096-104"
PACK_TYPE"0402"
VOLTAGE"16V"
TOLERANCE"10%"
MATERIAL"X7R"
NO_XNET_CONNECTION"1"
SEC"1"
SEC_TYPE"0402"
SPOF"TRUE"
ROOM"PVCCIN_CPU0_PWR_VR"
CDS_LOCATION"C4D9"
CDS_LIB"mstr_discrete";
"A"
$PN"1"47;
"B"
$PN"2"43;
%"CAPP"
"1","(-2750,2600)","0","mstr_discrete","I30";
;
CDS_SEC"1"
VOLTAGE"2.5V"
TOLERANCE"20%"
VALUE"470UF"
PACK_TYPE"3018"
MATERIAL"ALUM"
LOCATION"C6P18"
GROUP"PWR_BULK_CAP"
PART_NUMBER"699013-049"
SEC_TYPE"3018"
SEC"1"
BOM_COST"PROC_VRD_VCCIN_CPU0"
CDS_LOCATION"C6P18"
ROOM"PVCCIN_CPU0_DECAP_VR"
CDS_LIB"mstr_discrete";
"B"
$PN"2"8;
"A"
$PN"1"11;
%"CAPP"
"1","(-3200,2600)","0","mstr_discrete","I32";
;
CDS_SEC"1"
VALUE"470UF"
PART_NUMBER"699013-049"
MATERIAL"ALUM"
PACK_TYPE"3018"
LOCATION"C6P8"
TOLERANCE"20%"
VOLTAGE"2.5V"
GROUP"PWR_BULK_CAP"
SEC_TYPE"3018"
SEC"1"
BOM_COST"PROC_VRD_VCCIN_CPU0"
ROOM"PVCCIN_CPU0_DECAP_VR"
CDS_LOCATION"C6P8"
CDS_LIB"mstr_discrete";
"B"
$PN"2"8;
"A"
$PN"1"11;
%"PVCCIN_CPU0"
"1","(-3625,2875)","0","mstr_symbols","I33";
;
HDL_POWER"PVCCIN_CPU0"
BODY_TYPE"PLUMBING"
CDS_LIB"mstr_symbols"
VOLTAGE"2.0V";
"G\NAC"11;
%"CAPP"
"1","(-3625,2600)","0","mstr_discrete","I34";
;
CDS_SEC"1"
VOLTAGE"2.5V"
MATERIAL"ALUM"
PACK_TYPE"3018"
TOLERANCE"20%"
VALUE"470UF"
LOCATION"C6N9"
PART_NUMBER"699013-049"
GROUP"PWR_BULK_CAP"
SEC_TYPE"3018"
BOM_COST"PROC_VRD_VCCIN_CPU0"
SEC"1"
CDS_LOCATION"C6N9"
ROOM"PVCCIN_CPU0_DECAP_VR"
CDS_LIB"mstr_discrete";
"B"
$PN"2"8;
"A"
$PN"1"11;
%"VCC_CORE"
"1","(-6550,4600)","0","mstr_symbols","I39";
;
HDL_POWER"VR_FET_SW_P12V_STBY_PVCCIN_CPU0"
CDS_LIB"mstr_symbols";
"A"12;
%"CAP"
"1","(-4600,4150)","0","mstr_discrete","I40";
;
CDS_SEC"1"
MATERIAL"X7R"
LOCATION"C4D13"
VALUE"0.22UF"
VOLTAGE"16V"
TOLERANCE"10%"
PART_NUMBER"A36096-155"
PACK_TYPE"0402"
SEC_TYPE"0402"
CDS_LIB"mstr_discrete"
SEC"1"
CDS_LOCATION"C4D13"
ROOM"PVCCIN_CPU0_PWR_VR";
"A"
$PN"1"17;
"B"
$PN"2"13;
%"CAP"
"1","(-5800,3550)","2","mstr_discrete","I42";
;
CDS_SEC"1"
LOCATION"C4D28"
VALUE"0.220UF"
VOLTAGE"16V"
TOLERANCE"10%"
MATERIAL"X7R"
PART_NUMBER"A36096-104"
PACK_TYPE"0402"
NO_XNET_CONNECTION"1"
ROOM"PVCCIN_CPU0_PWR_VR"
CDS_LOCATION"C4D28"
SEC"1"
SPOF"TRUE"
SEC_TYPE"0402"
CDS_LIB"mstr_discrete";
"A"
$PN"1"26;
"B"
$PN"2"25;
%"CAP"
"1","(-5475,4150)","0","mstr_discrete","I45";
;
CDS_SEC"1"
VALUE"1.0UF"
TOLERANCE"10%"
MATERIAL"X6S"
PACK_TYPE"0402"
PART_NUMBER"D97712-011"
VOLTAGE"16V"
LOCATION"C4D16"
SEC_TYPE"0402"
SEC"1"
CDS_LIB"mstr_discrete"
CDS_LOCATION"C4D16"
ROOM"PVCCIN_CPU0_PWR_VR";
"A"
$PN"1"40;
"B"
$PN"2"13;
%"CAP_A"
"1","(-5775,4150)","0","dev_discrete","I46";
;
LOCATION"C4D35"
TOLERANCE"10%"
MATERIAL"X7R"
PART_NUMBER"A36096-030"
VALUE"0.1UF"
VOLTAGE"16V"
PACK_TYPE"0402V"
SEC"1"
SEC_TYPE"0402V"
ROOM"PVCCIN_CPU0_PWR_VR"
CDS_SEC"1"
CDS_LOCATION"C4D35"
CDS_LIB"dev_discrete";
"B"
$PN"2"13;
"A"
$PN"1"12;
%"CAP"
"1","(-6050,4150)","0","mstr_discrete","I47";
;
CDS_SEC"1"
TOLERANCE"10%"
VALUE"1.0UF"
LOCATION"C4D30"
MATERIAL"X6S"
VOLTAGE"16V"
PART_NUMBER"D97712-011"
PACK_TYPE"0402"
ROOM"PVCCIN_CPU0_PWR_VR"
SEC"1"
SEC_TYPE"0402"
CDS_LIB"mstr_discrete"
CDS_LOCATION"C4D30";
"A"
$PN"1"12;
"B"
$PN"2"13;
%"CAP"
"1","(-4825,1475)","0","mstr_discrete","I48";
;
CDS_SEC"1"
TOLERANCE"10%"
MATERIAL"X7R"
PACK_TYPE"0402"
VALUE"0.22UF"
LOCATION"C4D5"
VOLTAGE"16V"
PART_NUMBER"A36096-155"
SEC_TYPE"0402"
SEC"1"
CDS_LOCATION"C4D5"
ROOM"PVCCIN_CPU0_PWR_VR"
CDS_LIB"mstr_discrete";
"A"
$PN"1"18;
"B"
$PN"2"15;
%"CAP"
"1","(-5675,1475)","0","mstr_discrete","I51";
;
CDS_SEC"1"
LOCATION"C4D7"
PART_NUMBER"D97712-011"
PACK_TYPE"0402"
MATERIAL"X6S"
TOLERANCE"10%"
VALUE"1.0UF"
VOLTAGE"16V"
SEC_TYPE"0402"
SEC"1"
CDS_LOCATION"C4D7"
ROOM"PVCCIN_CPU0_PWR_VR"
CDS_LIB"mstr_discrete";
"A"
$PN"1"38;
"B"
$PN"2"15;
%"CAP_A"
"1","(-5975,1475)","0","dev_discrete","I52";
;
LOCATION"C4D11"
MATERIAL"X7R"
PACK_TYPE"0402V"
TOLERANCE"10%"
PART_NUMBER"A36096-030"
VALUE"0.1UF"
VOLTAGE"16V"
CDS_LIB"dev_discrete"
ROOM"PVCCIN_CPU0_PWR_VR"
CDS_LOCATION"C4D11"
CDS_SEC"1"
SEC_TYPE"0402V"
SEC"1";
"B"
$PN"2"15;
"A"
$PN"1"14;
%"CAP"
"1","(-6250,1475)","0","mstr_discrete","I53";
;
CDS_SEC"1"
LOCATION"C4D10"
PART_NUMBER"D97712-011"
VALUE"1.0UF"
VOLTAGE"16V"
MATERIAL"X6S"
TOLERANCE"10%"
PACK_TYPE"0402"
ROOM"PVCCIN_CPU0_PWR_VR"
SEC"1"
SEC_TYPE"0402"
CDS_LOCATION"C4D10"
CDS_LIB"mstr_discrete";
"A"
$PN"1"14;
"B"
$PN"2"15;
%"CAP"
"1","(-7000,4175)","0","mstr_discrete","I54";
;
CDS_SEC"1"
TOLERANCE"10%"
VALUE"10UF"
VOLTAGE"16V"
PART_NUMBER"C95333-007"
PACK_TYPE"0805"
LOCATION"C6P19"
MATERIAL"X6S"
ROOM"PVCCIN_CPU0_PWR_VR"
CDS_LOCATION"C6P19"
SEC"1"
SEC_TYPE"0805"
CDS_LIB"mstr_discrete";
"A"
$PN"1"12;
"B"
$PN"2"13;
%"GND"
"1","(-7000,3725)","0","mstr_symbols","I56";
;
HDL_POWER"GND"
BODY_TYPE"PLUMBING"
ROOM"PVCCIN_CPU0_PWR_VR"
BOM_COST"PROC_VRD_VCCIN_CPU0"
VOLTAGE"0"
CDS_LIB"mstr_symbols"
SIZE"1B";
"A\NAC"13;
%"CAP"
"1","(-6550,1475)","0","mstr_discrete","I57";
;
CDS_SEC"1"
VOLTAGE"16V"
TOLERANCE"10%"
MATERIAL"X6S"
LOCATION"C6P20"
VALUE"10UF"
PART_NUMBER"C95333-007"
PACK_TYPE"0805"
CDS_LIB"mstr_discrete"
CDS_LOCATION"C6P20"
SEC_TYPE"0805"
SEC"1"
ROOM"PVCCIN_CPU0_PWR_VR";
"A"
$PN"1"14;
"B"
$PN"2"15;
%"CAP"
"1","(-6825,1475)","0","mstr_discrete","I58";
;
CDS_SEC"1"
VOLTAGE"16V"
PACK_TYPE"0805"
PART_NUMBER"C95333-007"
MATERIAL"X6S"
TOLERANCE"10%"
VALUE"10UF"
LOCATION"C6P15"
ROOM"PVCCIN_CPU0_PWR_VR"
CDS_LOCATION"C6P15"
SEC"1"
SEC_TYPE"0805"
CDS_LIB"mstr_discrete";
"A"
$PN"1"14;
"B"
$PN"2"15;
%"CAP"
"1","(-7100,1475)","0","mstr_discrete","I59";
;
CDS_SEC"1"
LOCATION"C6P7"
VOLTAGE"16V"
VALUE"10UF"
TOLERANCE"10%"
MATERIAL"X6S"
PART_NUMBER"C95333-007"
PACK_TYPE"0805"
CDS_LIB"mstr_discrete"
SEC_TYPE"0805"
SEC"1"
CDS_LOCATION"C6P7"
ROOM"PVCCIN_CPU0_PWR_VR";
"A"
$PN"1"14;
"B"
$PN"2"15;
%"VCC_CORE"
"1","(-6650,1900)","0","mstr_symbols","I61";
;
HDL_POWER"VR_FET_SW_P12V_STBY_PVCCIN_CPU0"
CDS_LIB"mstr_symbols";
"A"14;
%"GND"
"1","(-7100,1000)","0","mstr_symbols","I62";
;
HDL_POWER"GND"
BODY_TYPE"PLUMBING"
SIZE"1B"
ROOM"PVCCIN_CPU0_PWR_VR"
BOM_COST"PROC_VRD_VCCIN_CPU0"
CDS_LIB"mstr_symbols"
VOLTAGE"0";
"A\NAC"15;
%"GND"
"1","(-2550,525)","0","mstr_symbols","I63";
;
HDL_POWER"GND"
BODY_TYPE"PLUMBING"
VOLTAGE"0"
CDS_LIB"mstr_symbols"
SIZE"1B"
BOM_COST"PROC_VRD_VCCIN_CPU0"
ROOM"PVCCIN_CPU0_PWR_VR";
"A\NAC"16;
%"P5V_STBY"
"1","(-4400,4875)","0","mstr_symbols","I64";
;
HDL_POWER"P5V_STBY"
BODY_TYPE"PLUMBING"
SIZE"1B"
CDS_LIB"mstr_symbols"
VOLTAGE"5.0V";
"G\NAC"17;
%"P5V_STBY"
"1","(-4375,2125)","0","mstr_symbols","I65";
;
HDL_POWER"P5V_STBY"
BODY_TYPE"PLUMBING"
VOLTAGE"5.0V"
CDS_LIB"mstr_symbols"
SIZE"1B";
"G\NAC"18;
%"CAP_A"
"1","(-800,3450)","0","dev_discrete","I66";
;
TOLERANCE"20%"
VOLTAGE"4V"
VALUE"22.0UF"
LOCATION"C6P21"
PACK_TYPE"0603V"
MATERIAL"X6S"
GROUP"PWR_MLCC_CAP"
PART_NUMBER"E15431-004"
CDS_LIB"dev_discrete"
CDS_SEC"1"
CDS_LOCATION"C6P21"
ROOM"PVCCIN_CPU0_PWR_VR"
SEC"1"
SEC_TYPE"0603V"
BOM_COST"PROC_VRD_VCCIN_CPU0";
"B"
$PN"2"7;
"A"
$PN"1"6;
%"RES"
"2","(-475,2550)","0","mstr_discrete","I67";
;
CDS_SEC"1"
PACK_TYPE"0603"
PART_NUMBER"G22026-038"
MATERIAL"CHIP"
WATTAGE"1/10W"
TOLERANCE"1%"
VALUE"100.0"
LOCATION"R4E13"
SEC_TYPE"0603"
BOM_COST"PROC_VRD_VCCIN_CPU0"
SEC"1"
CDS_LOCATION"R4E13"
ROOM"PVCCIN_CPU0_DECAP_VR"
CDS_LIB"mstr_discrete";
"A"
$PN"1"11;
"B"
$PN"2"8;
%"CAP_A"
"1","(-500,3450)","0","dev_discrete","I68";
;
VALUE"22.0UF"
VOLTAGE"4V"
TOLERANCE"20%"
LOCATION"C4D34"
MATERIAL"X6S"
PACK_TYPE"0603V"
GROUP"PWR_MLCC_CAP"
PART_NUMBER"E15431-004"
SEC_TYPE"0603V"
SEC"1"
CDS_LOCATION"C4D34"
CDS_LIB"dev_discrete"
CDS_SEC"1";
"B"
$PN"2"7;
"A"
$PN"1"6;
%"CAP_A"
"1","(-450,725)","0","dev_discrete","I69";
;
MATERIAL"X6S"
LOCATION"C4D4"
VOLTAGE"4V"
TOLERANCE"20%"
VALUE"22.0UF"
PACK_TYPE"0603V"
PART_NUMBER"E15431-004"
GROUP"PWR_MLCC_CAP"
SEC"1"
SEC_TYPE"0603V"
CDS_LOCATION"C4D4"
CDS_LIB"dev_discrete"
CDS_SEC"1";
"B"
$PN"2"9;
"A"
$PN"1"5;
%"IR354XX"
"1","(-3100,3925)","0","mstr_discrete","I70";
;
CDS_SEC"1"
LOCATION"EU4D3"
MATERIAL"IC"
PART_NUMBER"H73688-001"
PACK_TYPE"SM"
SEC_TYPE"SM"
SEC"1"
CDS_LOCATION"EU4D3"
CDS_LIB"mstr_discrete"
VALUE"IR35411";
"TOUT_FLT"
$PN"36"46;
"NC"
$PN"31"0;
"OCSET"
$PN"37"35;
"IOUT"
$PN"38"48;
"SW"
$PN"10"36;
"BOOST"
$PN"33"39;
"REFIN"
$PN"39"28;
"PWM"
$PN"34"27;
"PHASE"
$PN"32"25;
"VIN<0>"
$PN"25"12;
"VCC"
$PN"3"40;
"VIN<1>"
$PN"30"12;
"EN"
$PN"35"17;
"VDRV"
$PN"4"17;
"VOS"
$PN"1"6;
"LGND"
$PN"2"10;
"PGND<1>"
$PN"7"10;
"PGND<2>"
$PN"40"10;
"PGND<0>"
$PN"5"10;
"GL<0>"
$PN"6"44;
"GL<1>"
$PN"41"45;
%"IR354XX"
"1","(-3125,1200)","0","mstr_discrete","I71";
;
PART_NUMBER"H73688-001"
LOCATION"EU4D1"
MATERIAL"IC"
CDS_LOCATION"EU4D1"
CDS_LIB"mstr_discrete"
$SEC"1"
CDS_SEC"1"
PACK_TYPE"SM"
VALUE"IR35411";
"TOUT_FLT"
$PN"36"23;
"NC"
$PN"31"0;
"OCSET"
$PN"37"30;
"IOUT"
$PN"38"24;
"SW"
$PN"10"33;
"BOOST"
$PN"33"42;
"REFIN"
$PN"39"29;
"PWM"
$PN"34"32;
"PHASE"
$PN"32"43;
"VIN<0>"
$PN"25"14;
"VCC"
$PN"3"38;
"VIN<1>"
$PN"30"14;
"EN"
$PN"35"18;
"VDRV"
$PN"4"18;
"VOS"
$PN"1"5;
"LGND"
$PN"2"16;
"PGND<1>"
$PN"7"16;
"PGND<2>"
$PN"40"16;
"PGND<0>"
$PN"5"16;
"GL<0>"
$PN"6"31;
"GL<1>"
$PN"41"37;
%"RES"
"2","(-400,4100)","0","mstr_discrete","I89";
;
CDS_SEC"1"
CDS_LOCATION"R4D72"
LOCATION"R4D72"
VALUE"68.1K"
TOLERANCE"1%"
WATTAGE"1/16W"
MATERIAL"EMPTY"
PART_NUMBER"G21796-187"
PACK_TYPE"0402"
SEC_TYPE"0402"
SEC"1"
CDS_LIB"mstr_discrete";
"A"
$PN"1"35;
"B"
$PN"2"19;
%"GND"
"1","(-400,3875)","0","mstr_symbols","I90";
;
HDL_POWER"GND"
BODY_TYPE"PLUMBING"
VOLTAGE"0"
CDS_LIB"mstr_symbols"
SIZE"1B"
BOM_COST"PROC_VRD_VCCIN_CPU0"
ROOM"PVCCIN_CPU0_PWR_VR";
"A\NAC"19;
%"RES"
"2","(-375,1400)","0","mstr_discrete","I91";
;
CDS_SEC"1"
CDS_LOCATION"R4D71"
TOLERANCE"1%"
PACK_TYPE"0402"
MATERIAL"EMPTY"
WATTAGE"1/16W"
VALUE"68.1K"
LOCATION"R4D71"
PART_NUMBER"G21796-187"
SEC_TYPE"0402"
SEC"1"
CDS_LIB"mstr_discrete";
"A"
$PN"1"30;
"B"
$PN"2"20;
%"GND"
"1","(-375,1225)","0","mstr_symbols","I92";
;
HDL_POWER"GND"
BODY_TYPE"PLUMBING"
BOM_COST"PROC_VRD_VCCIN_CPU0"
ROOM"PVCCIN_CPU0_PWR_VR"
VOLTAGE"0"
CDS_LIB"mstr_symbols"
SIZE"1B";
"A\NAC"20;
%"CAP_A"
"1","(-3900,700)","0","dev_discrete","I93";
;
CDS_SEC"1"
CDS_LOCATION"CT40"
LOCATION"CT40"
VOLTAGE"16V"
VALUE"0.1UF"
MATERIAL"X7R"
TOLERANCE"10%"
POP"NOPOP"
PACK_TYPE"0402V"
PART_NUMBER"A36096-030"
SEC_TYPE"0402V"
SEC"1"
CDS_LIB"dev_discrete"
ROOM"PVCCIN_CPU0_PWR_VR";
"B"
$PN"2"21;
"A"
$PN"1"29;
%"GND"
"1","(-3900,425)","0","mstr_symbols","I94";
;
HDL_POWER"GND"
BODY_TYPE"PLUMBING"
VOLTAGE"0"
SIZE"1B"
BOM_COST"PROC_VRD_VCCIN_CPU0"
ROOM"PVCCIN_CPU0_PWR_VR"
CDS_LIB"mstr_symbols";
"A\NAC"21;
%"CAP_A"
"1","(-3900,3400)","0","dev_discrete","I96";
;
CDS_SEC"1"
CDS_LOCATION"CT39"
MATERIAL"X7R"
POP"NOPOP"
PACK_TYPE"0402V"
PART_NUMBER"A36096-030"
LOCATION"CT39"
TOLERANCE"10%"
VOLTAGE"16V"
VALUE"0.1UF"
SEC_TYPE"0402V"
SEC"1"
CDS_LIB"dev_discrete"
ROOM"PVCCIN_CPU0_PWR_VR";
"B"
$PN"2"22;
"A"
$PN"1"28;
%"GND"
"1","(-3900,3150)","0","mstr_symbols","I97";
;
HDL_POWER"GND"
BODY_TYPE"PLUMBING"
CDS_LIB"mstr_symbols"
ROOM"PVCCIN_CPU0_PWR_VR"
BOM_COST"PROC_VRD_VCCIN_CPU0"
SIZE"1B"
VOLTAGE"0";
"A\NAC"22;
%"CAP"
"1","(-1975,3950)","0","mstr_discrete","I99";
;
CDS_SEC"1"
CDS_LOCATION"CT37"
MATERIAL"X7R"
VALUE"1000PF"
VOLTAGE"50V"
TOLERANCE"10%"
LOCATION"CT37"
PART_NUMBER"A36096-046"
PACK_TYPE"0402LF"
POP"NOPOP"
SEC_TYPE"0402LF"
SEC"1"
CDS_LIB"mstr_discrete"
ROOM"VDDQ_KLM_PWR_VR";
"A"
$PN"1"46;
"B"
$PN"2"1;
END.
